Altium Designer Pick and Place Locations
C:\Users\<user>\Desktop\WorkNotes\Projects\PTP\Time-Appliance-Project-master\Time-Card\OSC\OCXO Daughtercard\ECAD\Project Outputs for OCXO_DaughterCard\Pick Place for OCXO_DaughterCard.csv

========================================================================================================================
File Design Information:

Date:       01/07/23
Time:       10:03
Revision:   Not in VersionControl
Variant:    No variations
Units used: mil

"Designator","Comment","Layer","Footprint","Center-X(mil)","Center-Y(mil)","Rotation","Description"
"R36","4.7K_1%_0402","TopLayer","RESC1005X40X25LL05T05","1231.299","1926.181","0","Chip Resistor, 4.7 KOhm, +/- 1%, 0.1 W, -55 to 155 degC, 0402 (1005 Metric), RoHS, Tape and Reel"
"R35","4.7K_1%_0402","TopLayer","RESC1005X40X25LL05T05","1335.630","1924.213","180","Chip Resistor, 4.7 KOhm, +/- 1%, 0.1 W, -55 to 155 degC, 0402 (1005 Metric), RoHS, Tape and Reel"
"R33","Yageo_RC0201JR-070RL","TopLayer","RESC0603X026N","1851.373","1715.458","180","RES, 0.0 OHM, 0.5A, 1/20W, 0201"
"C23","Samsung Electro-Mechanics_CL05B104JO5NNNC","TopLayer","CAPC1005X055N","1123.031","1809.646","270","CAP, CER, X7R, 0.1UF, 5%, 16V, 0402, 0.55MM T"
"C22","Murata_GRM188R61A106ME69D","TopLayer","CAPC1608X090N","1067.913","1796.457","270","CAP, CER, X5R, 10UF, 20%, 10V, 0603, 0.80MM T"
"R34","Yageo_RC0201FR-0710KL","TopLayer","RESC0603X026N","948.001","1813.386","270","RES, 10K OHM, 1%, 1/20W, 200PPM/C, 0201"
"Y5","SiTime_SiT5501AC-WU-33E0-10T","TopLayer","SITIME_SPL-086-CQFN-010-C07050_REV_DRAFT","1299.213","1776.772","90","OSC, MEMS, STRATUM 3E, 10.000MHZ, 10PPB STAB, LVCMOS, 3.3V, O/P EN, 7.0X5.0X2.2MM, CQFN-10"
"P14","4871","BottomLayer","Keystone_4871","374.015","279.528","180","Round Standoff Threaded #2-56 Steel 0.063" (1.60mm) 1/16""
"P13","4871","BottomLayer","Keystone_4871","374.015","1720.472","180","Round Standoff Threaded #2-56 Steel 0.063" (1.60mm) 1/16""
"P16","4871","BottomLayer","Keystone_4871","1625.984","1779.528","180","Round Standoff Threaded #2-56 Steel 0.063" (1.60mm) 1/16""
"P15","4871","BottomLayer","Keystone_4871","1598.425","161.417","180","Round Standoff Threaded #2-56 Steel 0.063" (1.60mm) 1/16""
"P12","Mill-Max_8600-0-05-80-00-00-03-0","BottomLayer","TH001V_109DIA_000mt_8600-0","755.905","1905.512","180","CONN, PC PIN, PRESS-FIT, 10.16MM LENGTH, TIN, TH"
"P11","Mill-Max_8600-0-05-80-00-00-03-0","BottomLayer","TH001V_109DIA_000mt_8600-0","637.795","1905.512","180","CONN, PC PIN, PRESS-FIT, 10.16MM LENGTH, TIN, TH"
"R32","0_1%_0402","BottomLayer","RESC1005X40X25NL05T10","1640.748","762.181","180",""
"R31","DNI_0_1%_0402","BottomLayer","RESC1005X40X25NL05T10","1586.614","778.913","270",""
"R30","0_1%_0402","BottomLayer","RESC1005X40X25NL05T10","1554.134","1134.842","90",""
"R29","DNI_0_1%_0402","BottomLayer","RESC1005X40X25NL05T10","1537.402","1080.435","180",""
"R26","0_1%_0402","BottomLayer","RESC1005X40X25NL05T10","1289.370","1491.142","90",""
"R25","0_1%_0402","BottomLayer","RESC1005X40X25NL05T10","1300.197","1432.087","0",""
"R24","0_1%_0402","BottomLayer","RESC1005X40X25NL05T10","1301.181","1315.945","0",""
"R22","DNI_0_1%_0402","BottomLayer","RESC1005X40X25NL05T10","1332.677","1490.158","270",""
"R21","DNI_0_1%_0402","BottomLayer","RESC1005X40X25NL05T10","1301.181","1394.629","180",""
"R20","DNI_0_1%_0402","BottomLayer","RESC1005X40X25NL05T10","1301.181","1353.347","180",""
"R19","0_1%_0402","BottomLayer","RESC1005X40X25NL05T10","124.016","1526.417","180",""
"R18","0_1%_0402","BottomLayer","RESC1005X40X25NL05T10","124.016","1487.047","180",""
"R17","0_1%_0402","BottomLayer","RESC1005X40X25NL05T10","124.016","1367.953","180",""
"R15","DNI_0_1%_0402","BottomLayer","RESC1005X40X25NL05T10","124.155","1566.772","0",""
"R28","4.7K_1%_0402","TopLayer","RESC1005X40X25LL05T05","426.181","1824.835","180","Chip Resistor, 4.7 KOhm, +/- 1%, 0.1 W, -55 to 155 degC, 0402 (1005 Metric), RoHS, Tape and Reel"
"R27","4.7K_1%_0402","TopLayer","RESC1005X40X25LL05T05","502.953","1824.835","0","Chip Resistor, 4.7 KOhm, +/- 1%, 0.1 W, -55 to 155 degC, 0402 (1005 Metric), RoHS, Tape and Reel"
"R23","0_5%_0603","BottomLayer","RESC1608X55X25ML10T15","1070.866","1336.614","180","Chip Resistor, 0 Ohm, +/- 5%, 0.1 W, -55 to 155 degC, 0603 (1608 Metric), RoHS, Tape and Reel"
"R16","0_5%_0603","BottomLayer","RESC1608X55X25ML10T15","452.756","1353.189","180","Chip Resistor, 0 Ohm, +/- 5%, 0.1 W, -55 to 155 degC, 0603 (1608 Metric), RoHS, Tape and Reel"
"U5","NXP_PCT2075TP,147","BottomLayer","SON50P300X200X80-HS-9N_EP160x160_IPC","1147.299","1449.903","0","SENSOR DIGITAL -55C-125C 8HWSON"
"R14","DNI_0_1%_0402","BottomLayer","RESC1005X40X25NL05T10","124.016","1447.677","0",""
"R13","DNI_0_1%_0402","BottomLayer","RESC1005X40X25NL05T10","124.016","1407.323","0",""
"R12","0_1%_0402","BottomLayer","RESC1005X40X25NL05T10","1018.722","766.501","90",""
"R11","0_1%_0402","BottomLayer","RESC1005X40X25NL05T10","959.667","767.564","90",""
"R10","DNI_0_1%_0402","BottomLayer","RESC1005X40X25NL05T10","899.130","784.218","0",""
"R9","DNI_0_1%_0402","BottomLayer","RESC1005X40X25NL05T10","1081.714","783.234","180",""
"C21","Samsung Electro-Mechanics_CL05B104JO5NNNC","BottomLayer","CAPC1005X055N","1187.008","1376.968","180","CAP, CER, X7R, 0.1UF, 5%, 16V, 0402, 0.55MM T"
"R7","Stackpole Electronics, Inc._HCJ0402ZT0R00","TopLayer","RESC1005X045N","1799.213","1641.246","90","RES, 0.0 OHM, 1/8W, 6.5A, 0402"
"R6","Stackpole Electronics, Inc._HCJ0402ZT0R00","TopLayer","RESC1005X045N","1168.724","1187.425","45","RES, 0.0 OHM, 1/8W, 6.5A, 0402"
"Y4","Rakon_RFPO45 US 10 LF","TopLayer","OSC004_600_970x750x430_RFP045","1319.882","1138.780","90","OSC, OCXO, RFPO45, 10 - 26MHZ, 10PPB STAB, HCMOS, 3.3V, 9.7X7.5X4.3MM, SMT"
"C20","Murata_GRM188D71A106MA73D","TopLayer","CAPC1608X100N","1271.654","861.461","0","CAP, CER, X7T, 10UF, 20%, 10V, 0603, 1.00MM T"
"C19","Samsung Electro-Mechanics_CL05B104JO5NNNC","TopLayer","CAPC1005X055N","1259.156","913.633","0","CAP, CER, X7R, 0.1UF, 5%, 16V, 0402, 0.55MM T"
"R8","Stackpole Electronics, Inc._HCJ0402ZT0R00","TopLayer","RESC1005X045N","1780.315","1715.458","0","RES, 0.0 OHM, 1/8W, 6.5A, 0402"
"Y3","Abracon_AOCJYR-10.000MHZ-M5625LF","TopLayer","OSC004_600_970x750x410_AOCJYR","1177.166","1374.998","270","OSC, OCXO, 10.000MHZ, 25PPB STAB, LVCMOS, 3.3V, 9.7X7.5X4.3MM, SMT"
"C18","Murata_GRM188D71A106MA73D","BottomLayer","CAPC1608X100N","1273.622","1624.016","0","CAP, CER, X7T, 10UF, 20%, 10V, 0603, 1.00MM T"
"C17","Samsung Electro-Mechanics_CL05B104JO5NNNC","TopLayer","CAPC1005X055N","1365.158","1474.409","270","CAP, CER, X7R, 0.1UF, 5%, 16V, 0402, 0.55MM T"
"U1","LMS1587IS-3.3/NOPB","TopLayer","KTT0003B_L","1107.061","331.059","0","3A Low Dropout Fast Response Regulators, 3-pin TO-263, Pb-Free"
"R2","DNI_0_1206","TopLayer","FP-RC1206-MFG","572.835","286.417","90","RES SMD 0 OHM JUMPER 1/4W 1206"
"C16","Kemet_T491B476K010AT","TopLayer","CAPMP3528X210N_T520","283.464","523.032","90","CAP TANT 47UF 10% 10V 1411"
"C5","Kemet_T491B476K010AT","TopLayer","CAPMP3528X210N_T520","569.882","528.543","90","CAP TANT 47UF 10% 10V 1411"
"C15","Kemet_T491B476K010AT","TopLayer","CAPMP3528X210N_T520","431.102","523.032","90","CAP TANT 47UF 10% 10V 1411"
"FL2","TDK_MPZ1608S601ATA00","BottomLayer","INDC1608X095N","789.961","720.296","90","FERRITE BEAD, 600 OHM @100MHZ, 25%, 1A, 0.150 OHM DCR, 0603, 0.95MM T"
"FL1","TDK_MPZ1608S601ATA00","BottomLayer","INDC1608X095N","868.597","1262.008","270","FERRITE BEAD, 600 OHM @100MHZ, 25%, 1A, 0.150 OHM DCR, 0603, 0.95MM T"
"U4","TI_DS90LV028AQMA/NOPB","BottomLayer","SOP127P600X175_8N","568.898","922.441","0","IC, RVCR, DS90LV028AQ-Q1, DUAL, DIFF, LVDS, 400MBPS, SOIC-8"
"U3","TI_DS90LV027AQMA/NOPB","BottomLayer","SOP127P600X175_8N","567.913","1155.512","180","IC, DRIVER, DS90LV027AQ, DUAL, DIFF, LVDS, 600MBPS, SOIC-8"
"R5","Yageo_RC0402FR-07100RL","BottomLayer","RESC1005X040N","389.764","871.850","90","RES SMD 100 OHM 1% 1/16W 0402"
"C14","Yageo_CC0402KRX7R7BB103","BottomLayer","CAPC1005X055N","675.266","736.614","270","CAP, CER, X7R, 0.01UF, 10%, 16V, 0402, 0.55MM T"
"C13","Samsung Electro-Mechanics_CL05B104JO5NNNC","BottomLayer","CAPC1005X055N","726.012","735.236","270","CAP, CER, X7R, 0.1UF, 5%, 16V, 0402, 0.55MM T"
"C12","Yageo_CC0402KRX7R7BB103","BottomLayer","CAPC1005X055N","814.088","1248.622","90","CAP, CER, X7R, 0.01UF, 10%, 16V, 0402, 0.55MM T"
"C11","Samsung Electro-Mechanics_CL05B104JO5NNNC","BottomLayer","CAPC1005X055N","760.500","1248.622","90","CAP, CER, X7R, 0.1UF, 5%, 16V, 0402, 0.55MM T"
"Y2","SiTime_SiT5711AC-KW-33E-10","TopLayer","SON150P700X619-10N_SiT5711","958.662","987.445","90","OSC, OCXO, 10.000MHZ, 5PPM STAB, LVCMOS/CLIPPED SINE, 3.3V, DFN-10"
"R4","Panasonic_ERJ-2RKF1003X","TopLayer","RESC1005X040N","859.449","774.694","180","RES, 100K OHM, 1%, 1/10W, 100PPM/C, 0402"
"C10","Murata_GRM188D71A106MA73D","TopLayer","CAPC1608X100N","872.047","1216.776","0","CAP, CER, X7T, 10UF, 20%, 10V, 0603, 1.00MM T"
"C9","Samsung Electro-Mechanics_CL05B104JO5NNNC","TopLayer","CAPC1005X055N","858.661","1163.626","0","CAP, CER, X7R, 0.1UF, 5%, 16V, 0402, 0.55MM T"
"C8","Murata_GRM188D71A106MA73D","BottomLayer","CAPC1608X100N","1505.906","1531.842","180","CAP, CER, X7T, 10UF, 20%, 10V, 0603, 1.00MM T"
"C7","Samsung Electro-Mechanics_CL05B104JO5NNNC","TopLayer","CAPC1005X055N","1697.507","1494.289","270","CAP, CER, X7R, 0.1UF, 5%, 16V, 0402, 0.55MM T"
"Y1","Rakon_ROD2522S2","TopLayer","OSC007_762_2540x2200x1230","1121.838","1163.271","180","OSC, OCXO, 10MHZ - 20MHZ, 0.5PPB STAB, 3.3V, 22.0X25.4X12.3MM, SMT"
"U2","Microchip_AT24MAC602-XHM-B","BottomLayer","TSSOP65P640X120-8N","368.576","1499.761","0","IC, EEPROM, AT24MAC602, 2K-BIT (256 X 8), 1MHZ, I2C, 1.7V - 5.5V, TSSOP-8"
"C6","Samsung Electro-Mechanics_CL05B104JO5NNNC","BottomLayer","CAPC1005X055N","464.663","1410.936","180","CAP, CER, X7R, 0.1UF, 5%, 16V, 0402, 0.55MM T"
"P10","Molex_539160208","BottomLayer","SM020V_50_730x310x337_000mt_53916","212.599","1000.000","90","CONN, B2B/FPC, HEADER, 20-POS, 0.5MM PITCH, 4.0MM H, VERT, GOLD, SMT"
"J2","Wurth_9774040243R","BottomLayer","TH000V_300DIAx400_001mt_9774040243R","1830.709","543.307","180","STANDOFF, ROUND, M2X0.4 STEEL 4MM, 9774040243R"
"J1","Wurth_9774040243R","BottomLayer","TH000V_300DIAx400_001mt_9774040243R","1830.709","1374.016","180","STANDOFF, ROUND, M2X0.4 STEEL 4MM, 9774040243R"
"R1","Stackpole Electronics, Inc._RMCF1210ZT0R00","TopLayer","RESC3225X070N","134.842","469.488","90","RES, 0.0 OHM, 3A, 1/2W, 1210"
"P9","Samtec_HTSW-102-07-T-S","TopLayer","TH002_254_508x254x838_000mt_HTSW","184.842","704.724","0","CONN, PIN, HEADER, 2POS, 2.54MM PITCH, 8.38MM H, VERT, TIN, TH"
"C4","Murata_GRM21BR61A226ME51L","TopLayer","CAPC2013X140N","756.890","186.024","270","CAP, CER, X5R, 22UF, 20%, 10V, 0805, 1.40MM T"
"C3","Murata_GRM21BR61A226ME51L","TopLayer","CAPC2013X140N","170.276","833.661","0","CAP, CER, X5R, 22UF, 20%, 10V, 0805, 1.40MM T"
"C2","Murata_GRM21BR61A226ME51L","TopLayer","CAPC2013X140N","170.276","933.071","0","CAP, CER, X5R, 22UF, 20%, 10V, 0805, 1.40MM T"
"C1","Samsung Electro-Mechanics_CL05B104JO5NNNC","TopLayer","CAPC1005X055N","664.370","186.181","270","CAP, CER, X7R, 0.1UF, 5%, 16V, 0402, 0.55MM T"
"P5","Mill-Max_8600-0-05-80-00-00-03-0","BottomLayer","TH001V_109DIA_000mt_8600-0","200.787","200.787","180","CONN, PC PIN, PRESS-FIT, 10.16MM LENGTH, TIN, TH"
"P4","Mill-Max_8600-0-05-80-00-00-03-0","BottomLayer","TH001V_109DIA_000mt_8600-0","1799.213","1000.000","180","CONN, PC PIN, PRESS-FIT, 10.16MM LENGTH, TIN, TH"
"P6","Mill-Max_8600-0-05-80-00-00-03-0","BottomLayer","TH001V_109DIA_000mt_8600-0","283.465","1905.512","180","CONN, PC PIN, PRESS-FIT, 10.16MM LENGTH, TIN, TH"
"P8","Mill-Max_8600-0-05-80-00-00-03-0","BottomLayer","TH001V_109DIA_000mt_8600-0","401.575","1905.512","180","CONN, PC PIN, PRESS-FIT, 10.16MM LENGTH, TIN, TH"
"P7","Mill-Max_8600-0-05-80-00-00-03-0","BottomLayer","TH001V_109DIA_000mt_8600-0","519.685","1905.512","180","CONN, PC PIN, PRESS-FIT, 10.16MM LENGTH, TIN, TH"
"P3","Mill-Max_8600-0-05-80-00-00-03-0","BottomLayer","TH001V_109DIA_000mt_8600-0","1799.213","1799.213","180","CONN, PC PIN, PRESS-FIT, 10.16MM LENGTH, TIN, TH"
"P1","Mill-Max_8600-0-05-80-00-00-03-0","BottomLayer","TH001V_109DIA_000mt_8600-0","1799.213","200.787","180","CONN, PC PIN, PRESS-FIT, 10.16MM LENGTH, TIN, TH"
"P2","Mill-Max_8600-0-05-80-00-00-03-0","BottomLayer","TH001V_109DIA_000mt_8600-0","200.787","1799.213","180","CONN, PC PIN, PRESS-FIT, 10.16MM LENGTH, TIN, TH"
